(kicad_pcb
	(version 20241229)
	(generator "pcbnew")
	(generator_version "9.0")
	(general
		(thickness 1.6642)
		(legacy_teardrops no)
	)
	(paper "A3")
	(title_block
		(title "PolarFire SoM")
		(date "2025-07-22")
		(rev "1.1.4")
		(company "Antmicro Ltd")
		(comment 1 "www.antmicro.com")
		(comment 9 "footprints 153-156 of 470")
	)
	(layers
		(0 "F.Cu" mixed)
		(4 "In1.Cu" power)
		(6 "In2.Cu" signal)
		(8 "In3.Cu" power)
		(10 "In4.Cu" signal)
		(12 "In5.Cu" power)
		(14 "In6.Cu" power)
		(16 "In7.Cu" signal)
		(18 "In8.Cu" power)
		(20 "In9.Cu" signal)
		(22 "In10.Cu" power)
		(24 "In11.Cu" signal)
		(26 "In12.Cu" signal)
		(2 "B.Cu" mixed)
		(9 "F.Adhes" user "F.Adhesive")
		(11 "B.Adhes" user "B.Adhesive")
		(13 "F.Paste" user)
		(15 "B.Paste" user)
		(5 "F.SilkS" user "F.Silkscreen")
		(7 "B.SilkS" user "B.Silkscreen")
		(1 "F.Mask" user)
		(3 "B.Mask" user)
		(17 "Dwgs.User" user "User.Drawings")
		(19 "Cmts.User" user "User.Comments")
		(21 "Eco1.User" user "User.Eco1")
		(23 "Eco2.User" user "User.Eco2")
		(25 "Edge.Cuts" user)
		(27 "Margin" user)
		(31 "F.CrtYd" user "F.Courtyard")
		(29 "B.CrtYd" user "B.Courtyard")
		(35 "F.Fab" user)
		(33 "B.Fab" user)
	)
	(footprint "antmicro-footprints:Fiducial_1mm_Mask2mm"
		(layer "B.Cu")
		(at 175.76 120.87 180)
		(descr "Circular Fiducial, 1mm bare copper, 3mm soldermask opening")
		(tags "fiducial")
		(property "Reference" "FD6"
			(at 0 1.4 0)
			(layer "B.SilkS")
			(hide yes)
			(effects
				(font
					(size 0.7 0.7)
					(thickness 0.15)
				)
				(justify left bottom mirror)
			)
		)
		(property "Value" "Fiducial_1mm_Mask2mm"
			(at 0 -2.2 0)
			(layer "B.Fab")
			(hide yes)
			(effects
				(font
					(size 0.7 0.7)
					(thickness 0.15)
				)
				(justify left bottom mirror)
			)
		)
		(property "Description" "Fiducial mask "
			(at 0 0 180)
			(layer "F.Fab")
			(hide yes)
			(effects
				(font
					(size 1.27 1.27)
					(thickness 0.15)
				)
			)
		)
		(property "Author" "Antmicro"
			(at 351.52 241.74 0)
			(layer "B.Fab")
			(hide yes)
			(effects
				(font
					(size 1 1)
					(thickness 0.15)
				)
				(justify mirror)
			)
		)
		(property "License" "Apache-2.0"
			(at 351.52 241.74 0)
			(layer "B.Fab")
			(hide yes)
			(effects
				(font
					(size 1 1)
					(thickness 0.15)
				)
				(justify mirror)
			)
		)
		(property "exclude_from_bom" ""
			(at 351.52 241.74 0)
			(layer "B.Fab")
			(hide yes)
			(effects
				(font
					(size 1 1)
					(thickness 0.15)
				)
				(justify mirror)
			)
		)
		(sheetfile "polarfire-som.kicad_sch")
		(attr board_only exclude_from_pos_files exclude_from_bom)
		(fp_circle
			(center 0 0)
			(end 1.24 0)
			(stroke
				(width 0.05)
				(type solid)
			)
			(fill no)
			(layer "B.CrtYd")
		)
		(fp_circle
			(center 0 0)
			(end 0.999 0)
			(stroke
				(width 0.15)
				(type solid)
			)
			(fill no)
			(layer "B.Fab")
		)
		(fp_text user "License: Apache-2.0"
			(at -1.25 -7.003 0)
			(layer "B.Fab")
			(effects
				(font
					(size 0.7 0.7)
					(thickness 0.15)
				)
				(justify left bottom mirror)
			)
		)
		(fp_text user "${REFERENCE}"
			(at -1.25 -4.603 0)
			(layer "B.Fab")
			(effects
				(font
					(size 0.7 0.7)
					(thickness 0.15)
				)
				(justify left bottom mirror)
			)
		)
		(fp_text user "Author: Antmicro"
			(at -1.25 -5.803 0)
			(layer "B.Fab")
			(effects
				(font
					(size 0.7 0.7)
					(thickness 0.15)
				)
				(justify left bottom mirror)
			)
		)
		(pad "" smd circle
			(at 0 0 180)
			(size 1 1)
			(layers "B.Cu" "B.Mask")
			(solder_mask_margin 0.5)
			(clearance 0.5)
		)
	)
	(footprint "antmicro-footprints:D_0402_1005Metric"
		(layer "B.Cu")
		(at 211.05 150.413 180)
		(property "Reference" "D4"
			(at -0.575 -1.312 0)
			(layer "B.SilkS")
			(effects
				(font
					(size 0.7 0.7)
					(thickness 0.15)
				)
				(justify left bottom mirror)
			)
		)
		(property "Value" "AXGD10402KR"
			(at -2.54 -2.54 0)
			(layer "B.Fab")
			(hide yes)
			(effects
				(font
					(size 0.7 0.7)
					(thickness 0.15)
				)
				(justify left bottom mirror)
			)
		)
		(property "Datasheet" "https://www.littelfuse.com/media?resourcetype=datasheets&itemid=020b2bf2-064c-4ff1-a898-b4ec805b2fea&filename=littelfuse-xtremeguard-axgd-datasheet"
			(at 0 0 180)
			(layer "F.Fab")
			(hide yes)
			(effects
				(font
					(size 1.27 1.27)
					(thickness 0.15)
				)
			)
		)
		(property "Description" "Bidirectional TVS, 30 kV,  0402, 24 V, 0.04 pF"
			(at 0 0 180)
			(layer "F.Fab")
			(hide yes)
			(effects
				(font
					(size 1.27 1.27)
					(thickness 0.15)
				)
			)
		)
		(property "Author" "Antmicro"
			(at 422.1 300.826 0)
			(layer "B.Fab")
			(hide yes)
			(effects
				(font
					(size 1 1)
					(thickness 0.15)
				)
				(justify mirror)
			)
		)
		(property "License" "Apache-2.0"
			(at 422.1 300.826 0)
			(layer "B.Fab")
			(hide yes)
			(effects
				(font
					(size 1 1)
					(thickness 0.15)
				)
				(justify mirror)
			)
		)
		(property "MPN" "AXGD10402KR"
			(at 422.1 300.826 0)
			(layer "B.Fab")
			(hide yes)
			(effects
				(font
					(size 1 1)
					(thickness 0.15)
				)
				(justify mirror)
			)
		)
		(property "Manufacturer" "Littelfuse"
			(at 422.1 300.826 0)
			(layer "B.Fab")
			(hide yes)
			(effects
				(font
					(size 1 1)
					(thickness 0.15)
				)
				(justify mirror)
			)
		)
		(property "Public" ""
			(at 422.1 300.826 0)
			(layer "B.Fab")
			(hide yes)
			(effects
				(font
					(size 1 1)
					(thickness 0.15)
				)
				(justify mirror)
			)
		)
		(sheetname "/USB/")
		(sheetfile "usb.kicad_sch")
		(attr smd)
		(fp_line
			(start 0.1 0.255)
			(end -0.1 0.255)
			(stroke
				(width 0.15)
				(type solid)
			)
			(layer "B.SilkS")
		)
		(fp_line
			(start -0.1 -0.255)
			(end 0.1 -0.255)
			(stroke
				(width 0.15)
				(type solid)
			)
			(layer "B.SilkS")
		)
		(fp_line
			(start -0.875 0.25)
			(end -0.875 -0.25)
			(stroke
				(width 0.15)
				(type solid)
			)
			(layer "B.SilkS")
		)
		(fp_rect
			(start -0.925 0.47)
			(end 0.925 -0.47)
			(stroke
				(width 0.05)
				(type default)
			)
			(fill no)
			(layer "B.CrtYd")
		)
		(fp_line
			(start 0.51 0.255)
			(end 0.51 -0.255)
			(stroke
				(width 0.15)
				(type solid)
			)
			(layer "B.Fab")
		)
		(fp_line
			(start 0.51 -0.255)
			(end -0.51 -0.255)
			(stroke
				(width 0.15)
				(type solid)
			)
			(layer "B.Fab")
		)
		(fp_line
			(start -0.2 0.25)
			(end -0.5 -0.05)
			(stroke
				(width 0.15)
				(type solid)
			)
			(layer "B.Fab")
		)
		(fp_line
			(start -0.51 0.255)
			(end 0.51 0.255)
			(stroke
				(width 0.15)
				(type solid)
			)
			(layer "B.Fab")
		)
		(fp_line
			(start -0.51 -0.255)
			(end -0.51 0.255)
			(stroke
				(width 0.15)
				(type solid)
			)
			(layer "B.Fab")
		)
		(fp_text user "${REFERENCE}"
			(at -2.54 -4.54 0)
			(layer "B.Fab")
			(effects
				(font
					(size 0.7 0.7)
					(thickness 0.15)
				)
				(justify left bottom mirror)
			)
		)
		(fp_text user "Author: Antmicro"
			(at -2.54 -6.94 0)
			(layer "B.Fab")
			(effects
				(font
					(size 0.7 0.7)
					(thickness 0.15)
				)
				(justify left bottom mirror)
			)
		)
		(fp_text user "License: Apache-2.0"
			(at -2.54 -5.74 0)
			(layer "B.Fab")
			(effects
				(font
					(size 0.7 0.7)
					(thickness 0.15)
				)
				(justify left bottom mirror)
			)
		)
		(pad "1" smd roundrect
			(at -0.48 0 180)
			(size 0.59 0.64)
			(layers "B.Cu" "B.Mask" "B.Paste")
			(roundrect_rratio 0.25)
			(net 417 "GND")
			(pinfunction "C")
			(pintype "passive")
		)
		(pad "2" smd roundrect
			(at 0.48 0 180)
			(size 0.59 0.64)
			(layers "B.Cu" "B.Mask" "B.Paste")
			(roundrect_rratio 0.25)
			(net 62 "USB_OTG_ID")
			(pinfunction "A")
			(pintype "passive")
		)
	)
	(footprint "antmicro-footprints:C_0402_1005Metric"
		(layer "B.Cu")
		(at 177.2 128.3 -90)
		(descr "Capacitor SMD 0402")
		(tags "capacitor SMD 0402")
		(property "Reference" "C126"
			(at 1.24 -3.205 180)
			(layer "B.SilkS")
			(effects
				(font
					(size 0.7 0.7)
					(thickness 0.15)
				)
				(justify left bottom mirror)
			)
		)
		(property "Value" "C_1u_0402"
			(at -1.022927 -2.155213 90)
			(layer "B.Fab")
			(hide yes)
			(effects
				(font
					(size 0.7 0.7)
					(thickness 0.15)
				)
				(justify left bottom mirror)
			)
		)
		(property "Datasheet" "https://product.tdk.com/en/search/capacitor/ceramic/mlcc/info?part_no=C1005X6S1A105K050BC"
			(at 0 0 270)
			(layer "F.Fab")
			(hide yes)
			(effects
				(font
					(size 1.27 1.27)
					(thickness 0.15)
				)
			)
		)
		(property "Description" "SMD Multilayer Ceramic Capacitor, 1 µF, 10 V, 0402 [1005 Metric], ± 10%, X6S, C"
			(at 0 0 270)
			(layer "F.Fab")
			(hide yes)
			(effects
				(font
					(size 1.27 1.27)
					(thickness 0.15)
				)
			)
		)
		(property "Author" "Antmicro"
			(at 48.9 305.5 0)
			(layer "B.Fab")
			(hide yes)
			(effects
				(font
					(size 1 1)
					(thickness 0.15)
				)
				(justify mirror)
			)
		)
		(property "Dielectric" "X5R"
			(at 48.9 305.5 0)
			(layer "B.Fab")
			(hide yes)
			(effects
				(font
					(size 1 1)
					(thickness 0.15)
				)
				(justify mirror)
			)
		)
		(property "License" "Apache-2.0"
			(at 48.9 305.5 0)
			(layer "B.Fab")
			(hide yes)
			(effects
				(font
					(size 1 1)
					(thickness 0.15)
				)
				(justify mirror)
			)
		)
		(property "MPN" "C1005X6S1A105K050BC"
			(at 48.9 305.5 0)
			(layer "B.Fab")
			(hide yes)
			(effects
				(font
					(size 1 1)
					(thickness 0.15)
				)
				(justify mirror)
			)
		)
		(property "Manufacturer" "TDK"
			(at 48.9 305.5 0)
			(layer "B.Fab")
			(hide yes)
			(effects
				(font
					(size 1 1)
					(thickness 0.15)
				)
				(justify mirror)
			)
		)
		(property "Public" ""
			(at 48.9 305.5 0)
			(layer "B.Fab")
			(hide yes)
			(effects
				(font
					(size 1 1)
					(thickness 0.15)
				)
				(justify mirror)
			)
		)
		(property "Val" "1u"
			(at 48.9 305.5 0)
			(layer "B.Fab")
			(hide yes)
			(effects
				(font
					(size 1 1)
					(thickness 0.15)
				)
				(justify mirror)
			)
		)
		(property "Voltage" "16V"
			(at 48.9 305.5 0)
			(layer "B.Fab")
			(hide yes)
			(effects
				(font
					(size 1 1)
					(thickness 0.15)
				)
				(justify mirror)
			)
		)
		(sheetname "/LPDDR4/")
		(sheetfile "lpddr.kicad_sch")
		(attr smd)
		(fp_rect
			(start -0.925 0.47)
			(end 0.925 -0.47)
			(stroke
				(width 0.05)
				(type default)
			)
			(fill no)
			(layer "B.CrtYd")
		)
		(fp_line
			(start -0.494 0.25)
			(end 0.504 0.25)
			(stroke
				(width 0.15)
				(type solid)
			)
			(layer "B.Fab")
		)
		(fp_line
			(start 0.504 0.25)
			(end 0.504 -0.248)
			(stroke
				(width 0.15)
				(type solid)
			)
			(layer "B.Fab")
		)
		(fp_line
			(start -0.494 -0.248)
			(end -0.494 0.25)
			(stroke
				(width 0.15)
				(type solid)
			)
			(layer "B.Fab")
		)
		(fp_line
			(start 0.504 -0.248)
			(end -0.494 -0.248)
			(stroke
				(width 0.15)
				(type solid)
			)
			(layer "B.Fab")
		)
		(fp_text user "License: Apache-2.0"
			(at -0.939 -5.799 90)
			(layer "B.Fab")
			(effects
				(font
					(size 0.7 0.7)
					(thickness 0.15)
				)
				(justify left bottom mirror)
			)
		)
		(fp_text user "Author: Antmicro"
			(at -0.939 -3.399 90)
			(layer "B.Fab")
			(effects
				(font
					(size 0.7 0.7)
					(thickness 0.15)
				)
				(justify left bottom mirror)
			)
		)
		(fp_text user "${REFERENCE}"
			(at -0.939 -4.599 90)
			(layer "B.Fab")
			(effects
				(font
					(size 0.7 0.7)
					(thickness 0.15)
				)
				(justify left bottom mirror)
			)
		)
		(pad "1" smd roundrect
			(at -0.48 0 270)
			(size 0.59 0.64)
			(layers "B.Cu" "B.Mask" "B.Paste")
			(roundrect_rratio 0.25)
			(net 417 "GND")
			(pintype "passive")
		)
		(pad "2" smd roundrect
			(at 0.48 0 270)
			(size 0.59 0.64)
			(layers "B.Cu" "B.Mask" "B.Paste")
			(roundrect_rratio 0.25)
			(net 2 "+1V1")
			(pintype "passive")
		)
	)
	(footprint "antmicro-footprints:C_0402_1005Metric"
		(layer "B.Cu")
		(at 219.725 144.895 -90)
		(descr "Capacitor SMD 0402")
		(tags "capacitor SMD 0402")
		(property "Reference" "C287"
			(at -9.92 -7.23 90)
			(layer "B.SilkS")
			(effects
				(font
					(size 0.7 0.7)
					(thickness 0.15)
				)
				(justify left bottom mirror)
			)
		)
		(property "Value" "C_10u_0402"
			(at -1.022927 -2.155213 90)
			(layer "B.Fab")
			(hide yes)
			(effects
				(font
					(size 0.7 0.7)
					(thickness 0.15)
				)
				(justify left bottom mirror)
			)
		)
		(property "Datasheet" "https://www.yageo.com/en/Chart/Download/pdf/CC0402MRX5R5BB106"
			(at 0 0 270)
			(layer "F.Fab")
			(hide yes)
			(effects
				(font
					(size 1.27 1.27)
					(thickness 0.15)
				)
			)
		)
		(property "Description" "SMD Multilayer Ceramic Capacitor, 10 µF, 6.3 V, 0402 [1005 Metric], ± 20%, X5R, CC Series"
			(at 0 0 270)
			(layer "F.Fab")
			(hide yes)
			(effects
				(font
					(size 1.27 1.27)
					(thickness 0.15)
				)
			)
		)
		(property "Author" "Antmicro"
			(at 74.83 364.62 0)
			(layer "B.Fab")
			(hide yes)
			(effects
				(font
					(size 1 1)
					(thickness 0.15)
				)
				(justify mirror)
			)
		)
		(property "Dielectric" ""
			(at 74.83 364.62 0)
			(layer "B.Fab")
			(hide yes)
			(effects
				(font
					(size 1 1)
					(thickness 0.15)
				)
				(justify mirror)
			)
		)
		(property "License" "Apache-2.0"
			(at 74.83 364.62 0)
			(layer "B.Fab")
			(hide yes)
			(effects
				(font
					(size 1 1)
					(thickness 0.15)
				)
				(justify mirror)
			)
		)
		(property "MPN" "CC0402MRX5R5BB106"
			(at 74.83 364.62 0)
			(layer "B.Fab")
			(hide yes)
			(effects
				(font
					(size 1 1)
					(thickness 0.15)
				)
				(justify mirror)
			)
		)
		(property "Manufacturer" "YAGEO"
			(at 74.83 364.62 0)
			(layer "B.Fab")
			(hide yes)
			(effects
				(font
					(size 1 1)
					(thickness 0.15)
				)
				(justify mirror)
			)
		)
		(property "Public" ""
			(at 74.83 364.62 0)
			(layer "B.Fab")
			(hide yes)
			(effects
				(font
					(size 1 1)
					(thickness 0.15)
				)
				(justify mirror)
			)
		)
		(property "Val" "10u"
			(at 74.83 364.62 0)
			(layer "B.Fab")
			(hide yes)
			(effects
				(font
					(size 1 1)
					(thickness 0.15)
				)
				(justify mirror)
			)
		)
		(property "Voltage" ""
			(at 74.83 364.62 0)
			(layer "B.Fab")
			(hide yes)
			(effects
				(font
					(size 1 1)
					(thickness 0.15)
				)
				(justify mirror)
			)
		)
		(sheetname "/WiFi_Bluetooth/")
		(sheetfile "wifi_bt.kicad_sch")
		(attr smd)
		(fp_rect
			(start -0.925 0.47)
			(end 0.925 -0.47)
			(stroke
				(width 0.05)
				(type default)
			)
			(fill no)
			(layer "B.CrtYd")
		)
		(fp_line
			(start -0.494 0.25)
			(end 0.504 0.25)
			(stroke
				(width 0.15)
				(type solid)
			)
			(layer "B.Fab")
		)
		(fp_line
			(start 0.504 0.25)
			(end 0.504 -0.248)
			(stroke
				(width 0.15)
				(type solid)
			)
			(layer "B.Fab")
		)
		(fp_line
			(start -0.494 -0.248)
			(end -0.494 0.25)
			(stroke
				(width 0.15)
				(type solid)
			)
			(layer "B.Fab")
		)
		(fp_line
			(start 0.504 -0.248)
			(end -0.494 -0.248)
			(stroke
				(width 0.15)
				(type solid)
			)
			(layer "B.Fab")
		)
		(fp_text user "${REFERENCE}"
			(at -0.939 -4.599 90)
			(layer "B.Fab")
			(effects
				(font
					(size 0.7 0.7)
					(thickness 0.15)
				)
				(justify left bottom mirror)
			)
		)
		(fp_text user "Author: Antmicro"
			(at -0.939 -3.399 90)
			(layer "B.Fab")
			(effects
				(font
					(size 0.7 0.7)
					(thickness 0.15)
				)
				(justify left bottom mirror)
			)
		)
		(fp_text user "License: Apache-2.0"
			(at -0.939 -5.799 90)
			(layer "B.Fab")
			(effects
				(font
					(size 0.7 0.7)
					(thickness 0.15)
				)
				(justify left bottom mirror)
			)
		)
		(pad "1" smd roundrect
			(at -0.48 0 270)
			(size 0.59 0.64)
			(layers "B.Cu" "B.Mask" "B.Paste")
			(roundrect_rratio 0.25)
			(net 417 "GND")
			(pintype "passive")
		)
		(pad "2" smd roundrect
			(at 0.48 0 270)
			(size 0.59 0.64)
			(layers "B.Cu" "B.Mask" "B.Paste")
			(roundrect_rratio 0.25)
			(net 50 "+3V3")
			(pintype "passive")
		)
	)
)
